# BASEBOARD_FAB2 (Tioga Pass) — schematic netlist excerpt (pin names and nets, part order shuffled) for the footprints in the layout excerpt that follows; sources: Cadence DE-HDL packaged netlist, KiCad conversion of Wiwynn_Tioga_Pass_MB.brd

R1G10  RES  0.0 5% CHIP  pkg 0402  page 223 : A = SVID_VDIO_PVDDQ_GHJ ; B = SVID_DIO1_CPU1_R

U7D2  GTL2014  IC  pkg SM  page 92
  DIR  = PD_GTL2104_DIR_0
  B0  = H_CPU_MSMI_G_N
  B1  = H_CPU0_FIVR_FAULT_G
  VREF  = P0V7_GTL2104_VREF_0
  B2  = H_CPU_ERR2_GTL_N
  B3  = H_CPU0_THERMTRIP_G_N
  GND(0)  = GND
  GND(1)  = GND
  A3  = FM_CPU0_THERMTRIP_LVT3_R_N
  A2  = FM_CPU_ERR2_LVT3_R_N
  GND(2)  = GND
  A1  = FM_CPU0_FIVR_FAULT_R_LVT3
  A0  = FM_CPU_MSMI_LVT3_R_N
  VCC  = P3V3

(kicad_pcb
	(version 20260206)
	(generator "pcbnew")
	(generator_version "10.0")
	(general
		(thickness 1.6)
		(legacy_teardrops no)
	)
	(paper "A4")
	(title_block
		(title "Wiwynn_Tioga_Pass_MB.brd")
		(comment 1 "Tioga Pass / footprints 2248-2249 of 4770")
	)
	(layers
		(0 "F.Cu" signal "TOP")
		(4 "In1.Cu" signal "L2GND")
		(6 "In2.Cu" signal "L3")
		(8 "In3.Cu" signal "L4GND")
		(10 "In4.Cu" signal "L5")
		(12 "In5.Cu" signal "L6GND")
		(14 "In6.Cu" signal "L7VCC")
		(16 "In7.Cu" signal "L8VCC")
		(18 "In8.Cu" signal "L9GND")
		(20 "In9.Cu" signal "L10")
		(22 "In10.Cu" signal "L11GND")
		(24 "In11.Cu" signal "L12")
		(26 "In12.Cu" signal "L13GND")
		(2 "B.Cu" signal "BOTTOM")
		(9 "F.Adhes" user "F.Adhesive")
		(11 "B.Adhes" user "B.Adhesive")
		(13 "F.Paste" user "Package Geometry/Pastemask Top")
		(15 "B.Paste" user "Package Geometry/Pastemask Bottom")
		(5 "F.SilkS" user "Ref Des/Silkscreen Top")
		(7 "B.SilkS" user "Ref Des/Silkscreen Bottom")
		(1 "F.Mask" user "Board Geometry/Soldermask Top")
		(3 "B.Mask" user "Board Geometry/Soldermask Bottom")
		(17 "Dwgs.User" user "User.Drawings")
		(19 "Cmts.User" user "User.Comments")
		(21 "Eco1.User" user "User.Eco1")
		(23 "Eco2.User" user "User.Eco2")
		(25 "Edge.Cuts" user "Board Geometry/Outline")
		(27 "Margin" user)
		(31 "F.CrtYd" user "Package Geometry/Place Bound Top")
		(29 "B.CrtYd" user "Package Geometry/Place Bound Bottom")
		(35 "F.Fab" user "Ref Des/Assembly Top")
		(33 "B.Fab" user "Ref Des/Assembly Bottom")
	)
	(footprint ""
		(layer "F.Cu")
		(at 386.326888 -78.388718)
		(property "Reference" "U7D2"
			(at -0.070104 -1.190752 0)
			(unlocked yes)
			(layer "F.SilkS")
			(effects
				(font
					(size 0.7874 0.5842)
					(thickness 0.1524)
				)
				(justify left)
			)
		)
		(property "Value" ""
			(at 0 0 0)
			(layer "F.Fab")
			(effects
				(font
					(size 1.27 1.27)
				)
			)
		)
		(duplicate_pad_numbers_are_jumpers no)
		(fp_line
			(start 1.5367 -0.64008)
			(end 4.4323 -0.64008)
			(stroke
				(width 0.1524)
				(type default)
			)
			(layer "F.SilkS")
		)
		(fp_line
			(start 1.5367 4.52628)
			(end 1.5367 -0.64008)
			(stroke
				(width 0.1524)
				(type default)
			)
			(layer "F.SilkS")
		)
		(fp_line
			(start 2.667 -0.64008)
			(end 2.667 0.49022)
			(stroke
				(width 0.1524)
				(type default)
			)
			(layer "F.SilkS")
		)
		(fp_line
			(start 2.667 0.49022)
			(end 3.302 0.49022)
			(stroke
				(width 0.1524)
				(type default)
			)
			(layer "F.SilkS")
		)
		(fp_line
			(start 3.302 0.49022)
			(end 3.302 -0.64008)
			(stroke
				(width 0.1524)
				(type default)
			)
			(layer "F.SilkS")
		)
		(fp_line
			(start 4.4323 -0.64008)
			(end 4.4323 4.52628)
			(stroke
				(width 0.1524)
				(type default)
			)
			(layer "F.SilkS")
		)
		(fp_line
			(start 4.4323 4.52628)
			(end 1.5367 4.52628)
			(stroke
				(width 0.1524)
				(type default)
			)
			(layer "F.SilkS")
		)
		(fp_circle
			(center -1.612138 -0.684784)
			(end -1.485138 -0.684784)
			(stroke
				(width 0.254)
				(type default)
			)
			(fill no)
			(layer "F.SilkS")
		)
		(fp_poly
			(pts
				(xy 0.7366 4.54152) (xy 0.7366 -0.64008) (xy 4.7244 -0.64008) (xy 5.2324 -0.64008) (xy 5.2324 4.54152)
				(xy 4.7244 4.54152)
			)
			(stroke
				(width 0)
				(type default)
			)
			(fill no)
			(layer "F.CrtYd")
		)
		(fp_line
			(start 0.7366 -0.64008)
			(end 5.2324 -0.64008)
			(stroke
				(width 0.1)
				(type default)
			)
			(layer "F.Fab")
		)
		(fp_line
			(start 0.7366 4.54152)
			(end 0.7366 -0.64008)
			(stroke
				(width 0.1)
				(type default)
			)
			(layer "F.Fab")
		)
		(fp_line
			(start 2.667 -0.64008)
			(end 2.667 0.49022)
			(stroke
				(width 0.1)
				(type default)
			)
			(layer "F.Fab")
		)
		(fp_line
			(start 2.667 0.49022)
			(end 3.302 0.49022)
			(stroke
				(width 0.1)
				(type default)
			)
			(layer "F.Fab")
		)
		(fp_line
			(start 3.302 0.49022)
			(end 3.302 -0.64008)
			(stroke
				(width 0.1)
				(type default)
			)
			(layer "F.Fab")
		)
		(fp_line
			(start 5.2324 -0.64008)
			(end 5.2324 4.54152)
			(stroke
				(width 0.1)
				(type default)
			)
			(layer "F.Fab")
		)
		(fp_line
			(start 5.2324 4.54152)
			(end 0.7366 4.54152)
			(stroke
				(width 0.1)
				(type default)
			)
			(layer "F.Fab")
		)
		(fp_circle
			(center -1.612138 -0.684784)
			(end -1.485138 -0.684784)
			(stroke
				(width 0.254)
				(type default)
			)
			(fill no)
			(layer "F.Fab")
		)
		(pad "1" smd rect
			(at 0 0)
			(size 2.159 0.381)
			(layers "F.Cu" "F.Mask" "F.Paste")
			(net "PD_GTL2104_DIR_0")
		)
		(pad "2" smd rect
			(at 0 0.65024)
			(size 2.159 0.381)
			(layers "F.Cu" "F.Mask" "F.Paste")
			(net "H_CPU_MSMI_G_N")
		)
		(pad "3" smd rect
			(at 0 1.30048)
			(size 2.159 0.381)
			(layers "F.Cu" "F.Mask" "F.Paste")
			(net "H_CPU0_FIVR_FAULT_G")
		)
		(pad "4" smd rect
			(at 0 1.95072)
			(size 2.159 0.381)
			(layers "F.Cu" "F.Mask" "F.Paste")
			(net "P0V7_GTL2104_VREF_0")
		)
		(pad "5" smd rect
			(at 0 2.60096)
			(size 2.159 0.381)
			(layers "F.Cu" "F.Mask" "F.Paste")
			(net "H_CPU_ERR2_GTL_N")
		)
		(pad "6" smd rect
			(at 0 3.2512)
			(size 2.159 0.381)
			(layers "F.Cu" "F.Mask" "F.Paste")
			(net "H_CPU0_THERMTRIP_G_N")
		)
		(pad "7" smd rect
			(at 0 3.90144)
			(size 2.159 0.381)
			(layers "F.Cu" "F.Mask" "F.Paste")
			(net "GND")
		)
		(pad "8" smd rect
			(at 5.969 3.90144)
			(size 2.159 0.381)
			(layers "F.Cu" "F.Mask" "F.Paste")
			(net "GND")
		)
		(pad "9" smd rect
			(at 5.969 3.2512)
			(size 2.159 0.381)
			(layers "F.Cu" "F.Mask" "F.Paste")
			(net "FM_CPU0_THERMTRIP_LVT3_R_N")
		)
		(pad "10" smd rect
			(at 5.969 2.60096)
			(size 2.159 0.381)
			(layers "F.Cu" "F.Mask" "F.Paste")
			(net "FM_CPU_ERR2_LVT3_R_N")
		)
		(pad "11" smd rect
			(at 5.969 1.95072)
			(size 2.159 0.381)
			(layers "F.Cu" "F.Mask" "F.Paste")
			(net "GND")
		)
		(pad "12" smd rect
			(at 5.969 1.30048)
			(size 2.159 0.381)
			(layers "F.Cu" "F.Mask" "F.Paste")
			(net "FM_CPU0_FIVR_FAULT_R_LVT3")
		)
		(pad "13" smd rect
			(at 5.969 0.65024)
			(size 2.159 0.381)
			(layers "F.Cu" "F.Mask" "F.Paste")
			(net "FM_CPU_MSMI_LVT3_R_N")
		)
		(pad "14" smd rect
			(at 5.969 0)
			(size 2.159 0.381)
			(layers "F.Cu" "F.Mask" "F.Paste")
			(net "P3V3")
		)
	)
	(footprint ""
		(layer "F.Cu")
		(at 10.362184 -3.532124 180)
		(property "Reference" "R1G10"
			(at 0 0 180)
			(layer "F.SilkS")
			(hide yes)
			(effects
				(font
					(size 1.27 1.27)
				)
			)
		)
		(property "Value" ""
			(at 0 0 180)
			(layer "F.Fab")
			(effects
				(font
					(size 1.27 1.27)
				)
			)
		)
		(duplicate_pad_numbers_are_jumpers no)
		(fp_rect
			(start 0.2794 0.9906)
			(end -0.2794 -0.1016)
			(stroke
				(width 0)
				(type default)
			)
			(fill no)
			(layer "F.CrtYd")
		)
		(fp_line
			(start 0.2794 0.9906)
			(end 0.2794 -0.1016)
			(stroke
				(width 0.1)
				(type default)
			)
			(layer "F.Fab")
		)
		(fp_line
			(start 0.2794 -0.1016)
			(end -0.2794 -0.1016)
			(stroke
				(width 0.1)
				(type default)
			)
			(layer "F.Fab")
		)
		(fp_line
			(start -0.2794 0.9906)
			(end 0.2794 0.9906)
			(stroke
				(width 0.1)
				(type default)
			)
			(layer "F.Fab")
		)
		(fp_line
			(start -0.2794 -0.1016)
			(end -0.2794 0.9906)
			(stroke
				(width 0.1)
				(type default)
			)
			(layer "F.Fab")
		)
		(pad "1" smd rect
			(at 0 0 180)
			(size 0.508 0.508)
			(layers "F.Cu" "F.Mask" "F.Paste")
			(net "SVID_VDIO_PVDDQ_GHJ")
		)
		(pad "2" smd rect
			(at 0 0.889 180)
			(size 0.508 0.508)
			(layers "F.Cu" "F.Mask" "F.Paste")
			(net "SVID_DIO1_CPU1_R")
		)
		(zone
			(layer "F.Cu")
			(hatch none 0.5)
			(connect_pads
				(clearance 0)
			)
			(min_thickness 0.25)
			(keepout
				(tracks not_allowed)
				(vias allowed)
				(pads allowed)
				(copperpour not_allowed)
				(footprints allowed)
			)
			(placement
				(enabled no)
				(sheetname "")
			)
			(fill
				(thermal_gap 0.5)
				(thermal_bridge_width 0.5)
				(island_removal_mode 0)
			)
			(polygon
				(pts
					(xy 10.108184 -4.167124) (xy 10.108184 -3.786124) (xy 10.616184 -3.786124) (xy 10.616184 -4.167124)
				)
			)
		)
		(zone
			(layer "F.Cu")
			(hatch none 0.5)
			(connect_pads
				(clearance 0)
			)
			(min_thickness 0.25)
			(keepout
				(tracks allowed)
				(vias not_allowed)
				(pads allowed)
				(copperpour not_allowed)
				(footprints allowed)
			)
			(placement
				(enabled no)
				(sheetname "")
			)
			(fill
				(thermal_gap 0.5)
				(thermal_bridge_width 0.5)
				(island_removal_mode 0)
			)
			(polygon
				(pts
					(xy 10.108184 -4.167124) (xy 10.108184 -3.786124) (xy 10.616184 -3.786124) (xy 10.616184 -4.167124)
				)
			)
		)
	)
)
